(kicad_pcb
	(version 20260206)
	(generator "pcbnew")
	(generator_version "10.0")
	(general
		(thickness 1.6)
		(legacy_teardrops no)
	)
	(paper "A4")
	(title_block
		(title "Wiwynn_Tioga_Pass_MB.brd")
		(comment 1 "Tioga Pass / footprints 1097-1103 of 4770")
	)
	(layers
		(0 "F.Cu" signal "TOP")
		(4 "In1.Cu" signal "L2GND")
		(6 "In2.Cu" signal "L3")
		(8 "In3.Cu" signal "L4GND")
		(10 "In4.Cu" signal "L5")
		(12 "In5.Cu" signal "L6GND")
		(14 "In6.Cu" signal "L7VCC")
		(16 "In7.Cu" signal "L8VCC")
		(18 "In8.Cu" signal "L9GND")
		(20 "In9.Cu" signal "L10")
		(22 "In10.Cu" signal "L11GND")
		(24 "In11.Cu" signal "L12")
		(26 "In12.Cu" signal "L13GND")
		(2 "B.Cu" signal "BOTTOM")
		(9 "F.Adhes" user "F.Adhesive")
		(11 "B.Adhes" user "B.Adhesive")
		(13 "F.Paste" user "Package Geometry/Pastemask Top")
		(15 "B.Paste" user "Package Geometry/Pastemask Bottom")
		(5 "F.SilkS" user "Ref Des/Silkscreen Top")
		(7 "B.SilkS" user "Ref Des/Silkscreen Bottom")
		(1 "F.Mask" user "Board Geometry/Soldermask Top")
		(3 "B.Mask" user "Board Geometry/Soldermask Bottom")
		(17 "Dwgs.User" user "User.Drawings")
		(19 "Cmts.User" user "User.Comments")
		(21 "Eco1.User" user "User.Eco1")
		(23 "Eco2.User" user "User.Eco2")
		(25 "Edge.Cuts" user "Board Geometry/Outline")
		(27 "Margin" user)
		(31 "F.CrtYd" user "Package Geometry/Place Bound Top")
		(29 "B.CrtYd" user "Package Geometry/Place Bound Bottom")
		(35 "F.Fab" user "Ref Des/Assembly Top")
		(33 "B.Fab" user "Ref Des/Assembly Bottom")
	)
	(footprint ""
		(layer "F.Cu")
		(at 7.366 -66.3702)
		(property "Reference" "R1D49"
			(at -3.556 -2.56413 0)
			(unlocked yes)
			(layer "F.SilkS")
			(effects
				(font
					(size 0.7874 0.5842)
					(thickness 0.1524)
				)
				(justify left)
			)
		)
		(property "Value" ""
			(at 0 0 0)
			(layer "F.Fab")
			(effects
				(font
					(size 1.27 1.27)
				)
			)
		)
		(duplicate_pad_numbers_are_jumpers no)
		(fp_circle
			(center -2.07264 -0.597154)
			(end -1.94564 -0.597154)
			(stroke
				(width 0.254)
				(type default)
			)
			(fill no)
			(layer "F.SilkS")
		)
		(fp_rect
			(start -0.8001 -0.31242)
			(end 5.8039 3.11658)
			(stroke
				(width 0)
				(type default)
			)
			(fill no)
			(layer "F.CrtYd")
		)
		(fp_line
			(start -0.8001 -0.31242)
			(end 5.8039 -0.31242)
			(stroke
				(width 0.1)
				(type default)
			)
			(layer "F.Fab")
		)
		(fp_line
			(start -0.8001 3.11658)
			(end -0.8001 -0.31242)
			(stroke
				(width 0.1)
				(type default)
			)
			(layer "F.Fab")
		)
		(fp_line
			(start 5.8039 -0.31242)
			(end 5.8039 3.11658)
			(stroke
				(width 0.1)
				(type default)
			)
			(layer "F.Fab")
		)
		(fp_line
			(start 5.8039 3.11658)
			(end -0.8001 3.11658)
			(stroke
				(width 0.1)
				(type default)
			)
			(layer "F.Fab")
		)
		(fp_circle
			(center -1.740916 -1.623822)
			(end -1.613916 -1.623822)
			(stroke
				(width 0.254)
				(type default)
			)
			(fill no)
			(layer "F.Fab")
		)
		(pad "1" smd rect
			(at 0 0)
			(size 3.4036 1.1938)
			(layers "F.Cu" "F.Mask" "F.Paste")
			(net "P12V_PSU")
		)
		(pad "2" smd rect
			(at 5.0038 0)
			(size 3.4036 1.1938)
			(layers "F.Cu" "F.Mask" "F.Paste")
			(net "P12V_MB0_SW")
		)
		(pad "3" smd rect
			(at 0 1.40208)
			(size 3.4036 0.6096)
			(layers "F.Cu" "F.Mask" "F.Paste")
			(net "P12V_HSC_SENP0")
		)
		(pad "4" smd rect
			(at 5.0038 1.40208)
			(size 3.4036 0.6096)
			(layers "F.Cu" "F.Mask" "F.Paste")
			(net "P12V_HSC_SENN0")
		)
		(pad "5" smd rect
			(at 0 2.80416)
			(size 3.4036 1.1938)
			(layers "F.Cu" "F.Mask" "F.Paste")
			(net "P12V_PSU")
		)
		(pad "6" smd rect
			(at 5.0038 2.80416)
			(size 3.4036 1.1938)
			(layers "F.Cu" "F.Mask" "F.Paste")
			(net "P12V_MB0_SW")
		)
		(zone
			(layer "F.Cu")
			(hatch none 0.5)
			(connect_pads
				(clearance 0)
			)
			(min_thickness 0.25)
			(keepout
				(tracks allowed)
				(vias not_allowed)
				(pads allowed)
				(copperpour not_allowed)
				(footprints allowed)
			)
			(placement
				(enabled no)
				(sheetname "")
			)
			(fill
				(thermal_gap 0.5)
				(thermal_bridge_width 0.5)
				(island_removal_mode 0)
			)
			(polygon
				(pts
					(xy 9.0678 -66.75628) (xy 9.0678 -62.96914) (xy 10.668 -62.96914) (xy 10.668 -66.9671) (xy 9.11352 -66.9671)
					(xy 9.0678 -66.9671)
				)
			)
		)
	)
	(footprint ""
		(layer "F.Cu")
		(at 276.000464 -3.3528 90)
		(property "Reference" "C5G18"
			(at 1.848866 0.752348 90)
			(unlocked yes)
			(layer "F.SilkS")
			(effects
				(font
					(size 1.27 0.9652)
					(thickness 0.1524)
				)
			)
		)
		(property "Value" ""
			(at 0 0 90)
			(layer "F.Fab")
			(effects
				(font
					(size 1.27 1.27)
				)
			)
		)
		(duplicate_pad_numbers_are_jumpers no)
		(fp_rect
			(start -0.500126 1.598422)
			(end 0.500126 -0.201422)
			(stroke
				(width 0)
				(type default)
			)
			(fill no)
			(layer "F.CrtYd")
		)
		(fp_line
			(start 0.500126 -0.201422)
			(end 0.500126 1.598422)
			(stroke
				(width 0.1)
				(type default)
			)
			(layer "F.Fab")
		)
		(fp_line
			(start -0.500126 -0.201422)
			(end 0.500126 -0.201422)
			(stroke
				(width 0.1)
				(type default)
			)
			(layer "F.Fab")
		)
		(fp_line
			(start 0.500126 1.598422)
			(end -0.500126 1.598422)
			(stroke
				(width 0.1)
				(type default)
			)
			(layer "F.Fab")
		)
		(fp_line
			(start -0.500126 1.598422)
			(end -0.500126 -0.201422)
			(stroke
				(width 0.1)
				(type default)
			)
			(layer "F.Fab")
		)
		(pad "1" smd rect
			(at 0 0)
			(size 0.889 0.9906)
			(layers "F.Cu" "F.Mask" "F.Paste")
			(net "PVDDQ_ABC")
		)
		(pad "2" smd rect
			(at 0 1.397)
			(size 0.889 0.9906)
			(layers "F.Cu" "F.Mask" "F.Paste")
			(net "GND")
		)
		(zone
			(layer "F.Cu")
			(hatch none 0.5)
			(connect_pads
				(clearance 0)
			)
			(min_thickness 0.25)
			(keepout
				(tracks allowed)
				(vias not_allowed)
				(pads allowed)
				(copperpour not_allowed)
				(footprints allowed)
			)
			(placement
				(enabled no)
				(sheetname "")
			)
			(fill
				(thermal_gap 0.5)
				(thermal_bridge_width 0.5)
				(island_removal_mode 0)
			)
			(polygon
				(pts
					(xy 276.952964 -2.8575) (xy 276.952964 -3.8481) (xy 276.444964 -3.8481) (xy 276.444964 -2.8575)
				)
			)
		)
		(zone
			(layer "F.Cu")
			(hatch none 0.5)
			(connect_pads
				(clearance 0)
			)
			(min_thickness 0.25)
			(keepout
				(tracks not_allowed)
				(vias allowed)
				(pads allowed)
				(copperpour not_allowed)
				(footprints allowed)
			)
			(placement
				(enabled no)
				(sheetname "")
			)
			(fill
				(thermal_gap 0.5)
				(thermal_bridge_width 0.5)
				(island_removal_mode 0)
			)
			(polygon
				(pts
					(xy 276.952964 -2.8575) (xy 276.952964 -3.8481) (xy 276.444964 -3.8481) (xy 276.444964 -2.8575)
				)
			)
		)
	)
	(footprint ""
		(layer "F.Cu")
		(at 393.2936 -0.2286)
		(property "Reference" "R8G11"
			(at 0 0 0)
			(layer "F.SilkS")
			(hide yes)
			(effects
				(font
					(size 1.27 1.27)
				)
			)
		)
		(property "Value" ""
			(at 0 0 0)
			(layer "F.Fab")
			(effects
				(font
					(size 1.27 1.27)
				)
			)
		)
		(duplicate_pad_numbers_are_jumpers no)
		(fp_poly
			(pts
				(xy -0.2794 -0.1016) (xy 0.2794 -0.1016) (xy 0.2794 0.9906) (xy -0.2794 0.9906)
			)
			(stroke
				(width 0)
				(type default)
			)
			(fill no)
			(layer "F.CrtYd")
		)
		(fp_line
			(start -0.2794 -0.1016)
			(end -0.2794 0.9906)
			(stroke
				(width 0.1)
				(type default)
			)
			(layer "F.Fab")
		)
		(fp_line
			(start -0.2794 0.9906)
			(end 0.2794 0.9906)
			(stroke
				(width 0.1)
				(type default)
			)
			(layer "F.Fab")
		)
		(fp_line
			(start 0.2794 -0.1016)
			(end -0.2794 -0.1016)
			(stroke
				(width 0.1)
				(type default)
			)
			(layer "F.Fab")
		)
		(fp_line
			(start 0.2794 0.9906)
			(end 0.2794 -0.1016)
			(stroke
				(width 0.1)
				(type default)
			)
			(layer "F.Fab")
		)
		(pad "1" smd rect
			(at 0 0)
			(size 0.508 0.508)
			(layers "F.Cu" "F.Mask" "F.Paste")
			(net "JTAG_PCH_PLD_TMS")
		)
		(pad "2" smd rect
			(at 0 0.889)
			(size 0.508 0.508)
			(layers "F.Cu" "F.Mask" "F.Paste")
			(net "JTAG_TMS")
		)
		(zone
			(layer "F.Cu")
			(hatch none 0.5)
			(connect_pads
				(clearance 0)
			)
			(min_thickness 0.25)
			(keepout
				(tracks allowed)
				(vias not_allowed)
				(pads allowed)
				(copperpour not_allowed)
				(footprints allowed)
			)
			(placement
				(enabled no)
				(sheetname "")
			)
			(fill
				(thermal_gap 0.5)
				(thermal_bridge_width 0.5)
				(island_removal_mode 0)
			)
			(polygon
				(pts
					(xy 393.0396 0.0254) (xy 393.5476 0.0254) (xy 393.5476 0.4064) (xy 393.0396 0.4064)
				)
			)
		)
		(zone
			(layer "F.Cu")
			(hatch none 0.5)
			(connect_pads
				(clearance 0)
			)
			(min_thickness 0.25)
			(keepout
				(tracks not_allowed)
				(vias allowed)
				(pads allowed)
				(copperpour not_allowed)
				(footprints allowed)
			)
			(placement
				(enabled no)
				(sheetname "")
			)
			(fill
				(thermal_gap 0.5)
				(thermal_bridge_width 0.5)
				(island_removal_mode 0)
			)
			(polygon
				(pts
					(xy 393.0396 0.4064) (xy 393.5476 0.4064) (xy 393.5476 0.0254) (xy 393.0396 0.0254)
				)
			)
		)
	)
	(footprint ""
		(layer "F.Cu")
		(at 465.6074 -1.9558)
		(property "Reference" "R25W154"
			(at -0.8382 -0.67818 0)
			(unlocked yes)
			(layer "F.SilkS")
			(effects
				(font
					(size 0.4064 0.254)
					(thickness 0.1524)
				)
				(justify left)
			)
		)
		(property "Value" ""
			(at 0 0 0)
			(layer "F.Fab")
			(effects
				(font
					(size 1.27 1.27)
				)
			)
		)
		(duplicate_pad_numbers_are_jumpers no)
		(fp_poly
			(pts
				(xy -0.2794 -0.1016) (xy 0.2794 -0.1016) (xy 0.2794 0.9906) (xy -0.2794 0.9906)
			)
			(stroke
				(width 0)
				(type default)
			)
			(fill no)
			(layer "F.CrtYd")
		)
		(fp_line
			(start -0.2794 -0.1016)
			(end -0.2794 0.9906)
			(stroke
				(width 0.1)
				(type default)
			)
			(layer "F.Fab")
		)
		(fp_line
			(start -0.2794 0.9906)
			(end 0.2794 0.9906)
			(stroke
				(width 0.1)
				(type default)
			)
			(layer "F.Fab")
		)
		(fp_line
			(start 0.2794 -0.1016)
			(end -0.2794 -0.1016)
			(stroke
				(width 0.1)
				(type default)
			)
			(layer "F.Fab")
		)
		(fp_line
			(start 0.2794 0.9906)
			(end 0.2794 -0.1016)
			(stroke
				(width 0.1)
				(type default)
			)
			(layer "F.Fab")
		)
		(pad "1" smd rect
			(at 0 0)
			(size 0.508 0.508)
			(layers "F.Cu" "F.Mask" "F.Paste")
			(net "SPI_BMC_BT_WP0_N")
		)
		(pad "2" smd rect
			(at 0 0.889)
			(size 0.508 0.508)
			(layers "F.Cu" "F.Mask" "F.Paste")
			(net "TPM_SPI_BMC_WP_N")
		)
		(zone
			(layer "F.Cu")
			(hatch none 0.5)
			(connect_pads
				(clearance 0)
			)
			(min_thickness 0.25)
			(keepout
				(tracks allowed)
				(vias not_allowed)
				(pads allowed)
				(copperpour not_allowed)
				(footprints allowed)
			)
			(placement
				(enabled no)
				(sheetname "")
			)
			(fill
				(thermal_gap 0.5)
				(thermal_bridge_width 0.5)
				(island_removal_mode 0)
			)
			(polygon
				(pts
					(xy 465.3534 -1.7018) (xy 465.8614 -1.7018) (xy 465.8614 -1.3208) (xy 465.3534 -1.3208)
				)
			)
		)
		(zone
			(layer "F.Cu")
			(hatch none 0.5)
			(connect_pads
				(clearance 0)
			)
			(min_thickness 0.25)
			(keepout
				(tracks not_allowed)
				(vias allowed)
				(pads allowed)
				(copperpour not_allowed)
				(footprints allowed)
			)
			(placement
				(enabled no)
				(sheetname "")
			)
			(fill
				(thermal_gap 0.5)
				(thermal_bridge_width 0.5)
				(island_removal_mode 0)
			)
			(polygon
				(pts
					(xy 465.3534 -1.3208) (xy 465.8614 -1.3208) (xy 465.8614 -1.7018) (xy 465.3534 -1.7018)
				)
			)
		)
	)
	(footprint ""
		(layer "F.Cu")
		(at 104.751378 -84.890102)
		(property "Reference" "C2D2"
			(at 0 0 0)
			(layer "F.SilkS")
			(hide yes)
			(effects
				(font
					(size 1.27 1.27)
				)
			)
		)
		(property "Value" ""
			(at 0 0 0)
			(layer "F.Fab")
			(effects
				(font
					(size 1.27 1.27)
				)
			)
		)
		(duplicate_pad_numbers_are_jumpers no)
		(fp_poly
			(pts
				(xy -0.4953 -0.2032) (xy 0.4953 -0.2032) (xy 0.4953 1.6002) (xy -0.4953 1.6002)
			)
			(stroke
				(width 0)
				(type default)
			)
			(fill no)
			(layer "F.CrtYd")
		)
		(fp_line
			(start -0.4953 -0.2032)
			(end 0.4953 -0.2032)
			(stroke
				(width 0.1)
				(type default)
			)
			(layer "F.Fab")
		)
		(fp_line
			(start -0.4953 1.6002)
			(end -0.4953 -0.2032)
			(stroke
				(width 0.1)
				(type default)
			)
			(layer "F.Fab")
		)
		(fp_line
			(start 0.4953 -0.2032)
			(end 0.4953 1.6002)
			(stroke
				(width 0.1)
				(type default)
			)
			(layer "F.Fab")
		)
		(fp_line
			(start 0.4953 1.6002)
			(end -0.4953 1.6002)
			(stroke
				(width 0.1)
				(type default)
			)
			(layer "F.Fab")
		)
		(pad "1" smd rect
			(at 0 0)
			(size 0.762 0.889)
			(layers "F.Cu" "F.Mask" "F.Paste")
			(net "PVDDQ_KLM")
		)
		(pad "2" smd rect
			(at 0 1.397)
			(size 0.762 0.889)
			(layers "F.Cu" "F.Mask" "F.Paste")
			(net "GND")
		)
		(zone
			(layer "F.Cu")
			(hatch none 0.5)
			(connect_pads
				(clearance 0)
			)
			(min_thickness 0.25)
			(keepout
				(tracks not_allowed)
				(vias allowed)
				(pads allowed)
				(copperpour not_allowed)
				(footprints allowed)
			)
			(placement
				(enabled no)
				(sheetname "")
			)
			(fill
				(thermal_gap 0.5)
				(thermal_bridge_width 0.5)
				(island_removal_mode 0)
			)
			(polygon
				(pts
					(xy 104.370378 -84.445602) (xy 105.132378 -84.445602) (xy 105.132378 -83.937602) (xy 104.370378 -83.937602)
				)
			)
		)
	)
	(footprint ""
		(layer "F.Cu")
		(at 350.012 -17.78 180)
		(property "Reference" "C7F18"
			(at 0 0 180)
			(layer "F.SilkS")
			(hide yes)
			(effects
				(font
					(size 1.27 1.27)
				)
			)
		)
		(property "Value" ""
			(at 0 0 180)
			(layer "F.Fab")
			(effects
				(font
					(size 1.27 1.27)
				)
			)
		)
		(duplicate_pad_numbers_are_jumpers no)
		(fp_poly
			(pts
				(xy 0.3048 -0.1016) (xy 0.3048 0.9906) (xy -0.3048 0.9906) (xy -0.3048 -0.1016)
			)
			(stroke
				(width 0)
				(type default)
			)
			(fill no)
			(layer "F.CrtYd")
		)
		(fp_line
			(start 0.3048 0.9906)
			(end 0.3048 -0.1016)
			(stroke
				(width 0.1)
				(type default)
			)
			(layer "F.Fab")
		)
		(fp_line
			(start 0.3048 -0.1016)
			(end -0.3048 -0.1016)
			(stroke
				(width 0.1)
				(type default)
			)
			(layer "F.Fab")
		)
		(fp_line
			(start -0.3048 0.9906)
			(end 0.3048 0.9906)
			(stroke
				(width 0.1)
				(type default)
			)
			(layer "F.Fab")
		)
		(fp_line
			(start -0.3048 -0.1016)
			(end -0.3048 0.9906)
			(stroke
				(width 0.1)
				(type default)
			)
			(layer "F.Fab")
		)
		(pad "1" smd rect
			(at 0 0 180)
			(size 0.508 0.508)
			(layers "F.Cu" "F.Mask" "F.Paste")
			(net "VR_PVDDQ_ABC_VDD")
		)
		(pad "2" smd rect
			(at 0 0.889 180)
			(size 0.508 0.508)
			(layers "F.Cu" "F.Mask" "F.Paste")
			(net "GND")
		)
		(zone
			(layer "F.Cu")
			(hatch none 0.5)
			(connect_pads
				(clearance 0)
			)
			(min_thickness 0.25)
			(keepout
				(tracks not_allowed)
				(vias allowed)
				(pads allowed)
				(copperpour not_allowed)
				(footprints allowed)
			)
			(placement
				(enabled no)
				(sheetname "")
			)
			(fill
				(thermal_gap 0.5)
				(thermal_bridge_width 0.5)
				(island_removal_mode 0)
			)
			(polygon
				(pts
					(xy 350.266 -18.415) (xy 349.758 -18.415) (xy 349.758 -18.034) (xy 350.266 -18.034)
				)
			)
		)
		(zone
			(layer "F.Cu")
			(hatch none 0.5)
			(connect_pads
				(clearance 0)
			)
			(min_thickness 0.25)
			(keepout
				(tracks allowed)
				(vias not_allowed)
				(pads allowed)
				(copperpour not_allowed)
				(footprints allowed)
			)
			(placement
				(enabled no)
				(sheetname "")
			)
			(fill
				(thermal_gap 0.5)
				(thermal_bridge_width 0.5)
				(island_removal_mode 0)
			)
			(polygon
				(pts
					(xy 350.266 -18.034) (xy 349.758 -18.034) (xy 349.758 -18.415) (xy 350.266 -18.415)
				)
			)
		)
	)
	(footprint ""
		(layer "F.Cu")
		(at 434.5051 -43.1038)
		(property "Reference" "R9F20"
			(at 0 0 0)
			(layer "F.SilkS")
			(hide yes)
			(effects
				(font
					(size 1.27 1.27)
				)
			)
		)
		(property "Value" ""
			(at 0 0 0)
			(layer "F.Fab")
			(effects
				(font
					(size 1.27 1.27)
				)
			)
		)
		(duplicate_pad_numbers_are_jumpers no)
		(fp_poly
			(pts
				(xy -0.2794 -0.1016) (xy 0.2794 -0.1016) (xy 0.2794 0.9906) (xy -0.2794 0.9906)
			)
			(stroke
				(width 0)
				(type default)
			)
			(fill no)
			(layer "F.CrtYd")
		)
		(fp_line
			(start -0.2794 -0.1016)
			(end -0.2794 0.9906)
			(stroke
				(width 0.1)
				(type default)
			)
			(layer "F.Fab")
		)
		(fp_line
			(start -0.2794 0.9906)
			(end 0.2794 0.9906)
			(stroke
				(width 0.1)
				(type default)
			)
			(layer "F.Fab")
		)
		(fp_line
			(start 0.2794 -0.1016)
			(end -0.2794 -0.1016)
			(stroke
				(width 0.1)
				(type default)
			)
			(layer "F.Fab")
		)
		(fp_line
			(start 0.2794 0.9906)
			(end 0.2794 -0.1016)
			(stroke
				(width 0.1)
				(type default)
			)
			(layer "F.Fab")
		)
		(pad "1" smd rect
			(at 0 0)
			(size 0.508 0.508)
			(layers "F.Cu" "F.Mask" "F.Paste")
			(net "PECI_BMC")
		)
		(pad "2" smd rect
			(at 0 0.889)
			(size 0.508 0.508)
			(layers "F.Cu" "F.Mask" "F.Paste")
			(net "GND")
		)
		(zone
			(layer "F.Cu")
			(hatch none 0.5)
			(connect_pads
				(clearance 0)
			)
			(min_thickness 0.25)
			(keepout
				(tracks allowed)
				(vias not_allowed)
				(pads allowed)
				(copperpour not_allowed)
				(footprints allowed)
			)
			(placement
				(enabled no)
				(sheetname "")
			)
			(fill
				(thermal_gap 0.5)
				(thermal_bridge_width 0.5)
				(island_removal_mode 0)
			)
			(polygon
				(pts
					(xy 434.2511 -42.8498) (xy 434.7591 -42.8498) (xy 434.7591 -42.4688) (xy 434.2511 -42.4688)
				)
			)
		)
		(zone
			(layer "F.Cu")
			(hatch none 0.5)
			(connect_pads
				(clearance 0)
			)
			(min_thickness 0.25)
			(keepout
				(tracks not_allowed)
				(vias allowed)
				(pads allowed)
				(copperpour not_allowed)
				(footprints allowed)
			)
			(placement
				(enabled no)
				(sheetname "")
			)
			(fill
				(thermal_gap 0.5)
				(thermal_bridge_width 0.5)
				(island_removal_mode 0)
			)
			(polygon
				(pts
					(xy 434.2511 -42.4688) (xy 434.7591 -42.4688) (xy 434.7591 -42.8498) (xy 434.2511 -42.8498)
				)
			)
		)
	)
)
